# S9S_MB_2U (Grand Teton) — schematic netlist excerpt (pin names and nets, part order shuffled) for the footprints in the layout excerpt that follows; sources: Cadence DE-HDL packaged netlist, KiCad conversion of 03242023_DA0F0TMBIJ0_F0T_Motherboard_J_brd_V01_OCP.brd

C1947  Q_CAP  0.1UF 25V 10% X7R  pkg 0402  page 217 : A = P3V3_AUX_FPGA_VCCIO5 ; B = GND
R240  Q_RES  0 5% CHIP  pkg 0402LF  page 121 : A = H_CPU1_PROCHOT_LVC1_R_N ; B = H_CPU1_PROCHOT_LVC1_N

(kicad_pcb
	(version 20260206)
	(generator "pcbnew")
	(generator_version "10.0")
	(general
		(thickness 1.6)
		(legacy_teardrops no)
	)
	(paper "A4")
	(title_block
		(title "03242023_DA0F0TMBIJ0_F0T_Motherboard_J_brd_V01_OCP.brd")
		(comment 1 "Grand Teton / footprints 4499-4500 of 6105")
	)
	(layers
		(0 "F.Cu" signal "TOP")
		(4 "In1.Cu" signal "GND")
		(6 "In2.Cu" signal "IN1")
		(8 "In3.Cu" signal "GND1")
		(10 "In4.Cu" signal "IN2")
		(12 "In5.Cu" signal "GND2")
		(14 "In6.Cu" signal "IN3")
		(16 "In7.Cu" signal "GND3")
		(18 "In8.Cu" signal "VCC")
		(20 "In9.Cu" signal "VCC1")
		(22 "In10.Cu" signal "GND4")
		(24 "In11.Cu" signal "IN4")
		(26 "In12.Cu" signal "GND5")
		(28 "In13.Cu" signal "IN5")
		(30 "In14.Cu" signal "GND6")
		(32 "In15.Cu" signal "IN6")
		(34 "In16.Cu" signal "GND7")
		(2 "B.Cu" signal "BOTTOM")
		(9 "F.Adhes" user "F.Adhesive")
		(11 "B.Adhes" user "B.Adhesive")
		(13 "F.Paste" user "Package Geometry/Pastemask Top")
		(15 "B.Paste" user "Package Geometry/Pastemask Bottom")
		(5 "F.SilkS" user "Ref Des/Silkscreen Top")
		(7 "B.SilkS" user "Ref Des/Silkscreen Bottom")
		(1 "F.Mask" user "Board Geometry/Soldermask Top")
		(3 "B.Mask" user "Board Geometry/Soldermask Bottom")
		(17 "Dwgs.User" user "User.Drawings")
		(19 "Cmts.User" user "User.Comments")
		(21 "Eco1.User" user "User.Eco1")
		(23 "Eco2.User" user "User.Eco2")
		(25 "Edge.Cuts" user "Board Geometry/Outline")
		(27 "Margin" user)
		(31 "F.CrtYd" user "Package Geometry/Place Bound Top")
		(29 "B.CrtYd" user "Package Geometry/Place Bound Bottom")
		(35 "F.Fab" user "Ref Des/Assembly Top")
		(33 "B.Fab" user "Ref Des/Assembly Bottom")
	)
	(footprint ""
		(layer "B.Cu")
		(at 173.04893 -102.707948)
		(property "Reference" "C1947"
			(at 0 0 0)
			(layer "B.SilkS")
			(hide yes)
			(effects
				(font
					(size 1.27 1.27)
				)
				(justify mirror)
			)
		)
		(property "Value" ""
			(at 0 0 0)
			(layer "B.Fab")
			(effects
				(font
					(size 1.27 1.27)
				)
				(justify mirror)
			)
		)
		(duplicate_pad_numbers_are_jumpers no)
		(fp_line
			(start -0.7874 -0.4064)
			(end -0.7874 0.4064)
			(stroke
				(width 0.1524)
				(type default)
			)
			(layer "B.SilkS")
		)
		(fp_line
			(start -0.7874 0.4064)
			(end 0.7874 0.4064)
			(stroke
				(width 0.1524)
				(type default)
			)
			(layer "B.SilkS")
		)
		(fp_line
			(start 0.7874 -0.4064)
			(end -0.7874 -0.4064)
			(stroke
				(width 0.1524)
				(type default)
			)
			(layer "B.SilkS")
		)
		(fp_line
			(start 0.7874 0.4064)
			(end 0.7874 -0.4064)
			(stroke
				(width 0.1524)
				(type default)
			)
			(layer "B.SilkS")
		)
		(fp_line
			(start -0.67945 -0.3048)
			(end -0.67945 0.3048)
			(stroke
				(width 0.1)
				(type default)
			)
			(layer "B.Fab")
		)
		(fp_line
			(start -0.67945 0.3048)
			(end -0.120396 0.3048)
			(stroke
				(width 0.1)
				(type default)
			)
			(layer "B.Fab")
		)
		(fp_line
			(start -0.12065 -0.3048)
			(end -0.67945 -0.3048)
			(stroke
				(width 0.1)
				(type default)
			)
			(layer "B.Fab")
		)
		(fp_line
			(start -0.12065 -0.2794)
			(end -0.12065 -0.3048)
			(stroke
				(width 0.1)
				(type default)
			)
			(layer "B.Fab")
		)
		(fp_line
			(start -0.120396 0.2794)
			(end 0.12065 0.2794)
			(stroke
				(width 0.1)
				(type default)
			)
			(layer "B.Fab")
		)
		(fp_line
			(start -0.120396 0.3048)
			(end -0.120396 0.2794)
			(stroke
				(width 0.1)
				(type default)
			)
			(layer "B.Fab")
		)
		(fp_line
			(start 0.12065 -0.305054)
			(end 0.12065 -0.2794)
			(stroke
				(width 0.1)
				(type default)
			)
			(layer "B.Fab")
		)
		(fp_line
			(start 0.12065 -0.2794)
			(end -0.12065 -0.2794)
			(stroke
				(width 0.1)
				(type default)
			)
			(layer "B.Fab")
		)
		(fp_line
			(start 0.12065 0.2794)
			(end 0.12065 0.3048)
			(stroke
				(width 0.1)
				(type default)
			)
			(layer "B.Fab")
		)
		(fp_line
			(start 0.12065 0.3048)
			(end 0.67945 0.3048)
			(stroke
				(width 0.1)
				(type default)
			)
			(layer "B.Fab")
		)
		(fp_line
			(start 0.67945 -0.305054)
			(end 0.12065 -0.305054)
			(stroke
				(width 0.1)
				(type default)
			)
			(layer "B.Fab")
		)
		(fp_line
			(start 0.67945 0.3048)
			(end 0.67945 -0.305054)
			(stroke
				(width 0.1)
				(type default)
			)
			(layer "B.Fab")
		)
		(pad "1" smd circle
			(at 0.40005 0 180)
			(size 0 0)
			(layers "B.Cu" "B.Mask" "B.Paste")
			(net "P3V3_AUX_FPGA_VCCIO5")
		)
		(pad "2" smd circle
			(at -0.40005 0 180)
			(size 0 0)
			(layers "B.Cu" "B.Mask" "B.Paste")
			(net "GND")
		)
	)
	(footprint ""
		(layer "B.Cu")
		(at 80.430624 -184.096152 -90)
		(property "Reference" "R240"
			(at 0 0 90)
			(layer "B.SilkS")
			(hide yes)
			(effects
				(font
					(size 1.27 1.27)
				)
				(justify mirror)
			)
		)
		(property "Value" ""
			(at 0 0 90)
			(layer "B.Fab")
			(effects
				(font
					(size 1.27 1.27)
				)
				(justify mirror)
			)
		)
		(duplicate_pad_numbers_are_jumpers no)
		(fp_line
			(start -0.7874 0.4064)
			(end 0.7874 0.4064)
			(stroke
				(width 0.1524)
				(type default)
			)
			(layer "B.SilkS")
		)
		(fp_line
			(start 0.7874 0.4064)
			(end 0.7874 -0.4064)
			(stroke
				(width 0.1524)
				(type default)
			)
			(layer "B.SilkS")
		)
		(fp_line
			(start -0.7874 -0.4064)
			(end -0.7874 0.4064)
			(stroke
				(width 0.1524)
				(type default)
			)
			(layer "B.SilkS")
		)
		(fp_line
			(start 0.7874 -0.4064)
			(end -0.7874 -0.4064)
			(stroke
				(width 0.1524)
				(type default)
			)
			(layer "B.SilkS")
		)
		(fp_line
			(start -0.67945 0.3048)
			(end -0.120396 0.3048)
			(stroke
				(width 0.1)
				(type default)
			)
			(layer "B.Fab")
		)
		(fp_line
			(start -0.120396 0.3048)
			(end -0.120396 0.2794)
			(stroke
				(width 0.1)
				(type default)
			)
			(layer "B.Fab")
		)
		(fp_line
			(start 0.12065 0.3048)
			(end 0.67945 0.3048)
			(stroke
				(width 0.1)
				(type default)
			)
			(layer "B.Fab")
		)
		(fp_line
			(start 0.67945 0.3048)
			(end 0.67945 -0.305054)
			(stroke
				(width 0.1)
				(type default)
			)
			(layer "B.Fab")
		)
		(fp_line
			(start -0.120396 0.2794)
			(end 0.12065 0.2794)
			(stroke
				(width 0.1)
				(type default)
			)
			(layer "B.Fab")
		)
		(fp_line
			(start 0.12065 0.2794)
			(end 0.12065 0.3048)
			(stroke
				(width 0.1)
				(type default)
			)
			(layer "B.Fab")
		)
		(fp_line
			(start -0.12065 -0.2794)
			(end -0.12065 -0.3048)
			(stroke
				(width 0.1)
				(type default)
			)
			(layer "B.Fab")
		)
		(fp_line
			(start 0.12065 -0.2794)
			(end -0.12065 -0.2794)
			(stroke
				(width 0.1)
				(type default)
			)
			(layer "B.Fab")
		)
		(fp_line
			(start -0.67945 -0.3048)
			(end -0.67945 0.3048)
			(stroke
				(width 0.1)
				(type default)
			)
			(layer "B.Fab")
		)
		(fp_line
			(start -0.12065 -0.3048)
			(end -0.67945 -0.3048)
			(stroke
				(width 0.1)
				(type default)
			)
			(layer "B.Fab")
		)
		(fp_line
			(start 0.12065 -0.305054)
			(end 0.12065 -0.2794)
			(stroke
				(width 0.1)
				(type default)
			)
			(layer "B.Fab")
		)
		(fp_line
			(start 0.67945 -0.305054)
			(end 0.12065 -0.305054)
			(stroke
				(width 0.1)
				(type default)
			)
			(layer "B.Fab")
		)
		(pad "1" smd circle
			(at 0.40005 0 90)
			(size 0 0)
			(layers "B.Cu" "B.Mask" "B.Paste")
			(net "H_CPU1_PROCHOT_LVC1_R_N")
		)
		(pad "2" smd circle
			(at -0.40005 0 90)
			(size 0 0)
			(layers "B.Cu" "B.Mask" "B.Paste")
			(net "H_CPU1_PROCHOT_LVC1_N")
		)
	)
)
